# BASEBOARD_FAB2 (Tioga Pass) — schematic netlist excerpt (pin names and nets, part order shuffled) for the footprints in the layout excerpt that follows; sources: Cadence DE-HDL packaged netlist, KiCad conversion of Wiwynn_Tioga_Pass_MB.brd

C22W29  SC22U16V5MX-4-GP  20%  pkg SMD-BCG5  page 212 : \1\ = VR_FET_SW_P12V_STBY_PVCCIO_CPU0 ; \2\ = GND
C7W9  SC22U16V5MX-4-GP  20%  pkg SMD-BCG5  page 220 : \1\ = VR_FET_SW_P12V_STBY_PVDDQ_DEF ; \2\ = GND
C25W36  CAP  4.7UF 6.3V 10% X6S  pkg 0603  page 149 : A = VCC_DACAV3V3 ; B = GND
R6U17  RES  665 1.0% CHIP  pkg 0402  page 99 : A = PVPP_GHJ ; B = SMB_DDR_GHJ_VPP_SCL_R

(kicad_pcb
	(version 20260206)
	(generator "pcbnew")
	(generator_version "10.0")
	(general
		(thickness 1.6)
		(legacy_teardrops no)
	)
	(paper "A4")
	(title_block
		(title "Wiwynn_Tioga_Pass_MB.brd")
		(comment 1 "Tioga Pass / footprints 2512-2515 of 4770")
	)
	(layers
		(0 "F.Cu" signal "TOP")
		(4 "In1.Cu" signal "L2GND")
		(6 "In2.Cu" signal "L3")
		(8 "In3.Cu" signal "L4GND")
		(10 "In4.Cu" signal "L5")
		(12 "In5.Cu" signal "L6GND")
		(14 "In6.Cu" signal "L7VCC")
		(16 "In7.Cu" signal "L8VCC")
		(18 "In8.Cu" signal "L9GND")
		(20 "In9.Cu" signal "L10")
		(22 "In10.Cu" signal "L11GND")
		(24 "In11.Cu" signal "L12")
		(26 "In12.Cu" signal "L13GND")
		(2 "B.Cu" signal "BOTTOM")
		(9 "F.Adhes" user "F.Adhesive")
		(11 "B.Adhes" user "B.Adhesive")
		(13 "F.Paste" user "Package Geometry/Pastemask Top")
		(15 "B.Paste" user "Package Geometry/Pastemask Bottom")
		(5 "F.SilkS" user "Ref Des/Silkscreen Top")
		(7 "B.SilkS" user "Ref Des/Silkscreen Bottom")
		(1 "F.Mask" user "Board Geometry/Soldermask Top")
		(3 "B.Mask" user "Board Geometry/Soldermask Bottom")
		(17 "Dwgs.User" user "User.Drawings")
		(19 "Cmts.User" user "User.Comments")
		(21 "Eco1.User" user "User.Eco1")
		(23 "Eco2.User" user "User.Eco2")
		(25 "Edge.Cuts" user "Board Geometry/Outline")
		(27 "Margin" user)
		(31 "F.CrtYd" user "Package Geometry/Place Bound Top")
		(29 "B.CrtYd" user "Package Geometry/Place Bound Bottom")
		(35 "F.Fab" user "Ref Des/Assembly Top")
		(33 "B.Fab" user "Ref Des/Assembly Bottom")
	)
	(footprint ""
		(layer "B.Cu")
		(at 166.751 4.445 180)
		(property "Reference" "R6U17"
			(at 0 0 0)
			(layer "B.SilkS")
			(hide yes)
			(effects
				(font
					(size 1.27 1.27)
				)
				(justify mirror)
			)
		)
		(property "Value" ""
			(at 0 0 0)
			(layer "B.Fab")
			(effects
				(font
					(size 1.27 1.27)
				)
				(justify mirror)
			)
		)
		(duplicate_pad_numbers_are_jumpers no)
		(fp_poly
			(pts
				(xy 0.2794 -0.1016) (xy -0.2794 -0.1016) (xy -0.2794 0.9906) (xy 0.2794 0.9906)
			)
			(stroke
				(width 0)
				(type default)
			)
			(fill no)
			(layer "B.CrtYd")
		)
		(fp_line
			(start 0.2794 0.9906)
			(end -0.2794 0.9906)
			(stroke
				(width 0.1)
				(type default)
			)
			(layer "B.Fab")
		)
		(fp_line
			(start 0.2794 -0.1016)
			(end 0.2794 0.9906)
			(stroke
				(width 0.1)
				(type default)
			)
			(layer "B.Fab")
		)
		(fp_line
			(start -0.2794 0.9906)
			(end -0.2794 -0.1016)
			(stroke
				(width 0.1)
				(type default)
			)
			(layer "B.Fab")
		)
		(fp_line
			(start -0.2794 -0.1016)
			(end 0.2794 -0.1016)
			(stroke
				(width 0.1)
				(type default)
			)
			(layer "B.Fab")
		)
		(pad "1" smd rect
			(at 0 0)
			(size 0.508 0.508)
			(layers "B.Cu" "B.Mask" "B.Paste")
			(net "PVPP_GHJ")
		)
		(pad "2" smd rect
			(at 0 0.889)
			(size 0.508 0.508)
			(layers "B.Cu" "B.Mask" "B.Paste")
			(net "SMB_DDR_GHJ_VPP_SCL_R")
		)
		(zone
			(layer "B.Cu")
			(hatch none 0.5)
			(connect_pads
				(clearance 0)
			)
			(min_thickness 0.25)
			(keepout
				(tracks not_allowed)
				(vias allowed)
				(pads allowed)
				(copperpour not_allowed)
				(footprints allowed)
			)
			(placement
				(enabled no)
				(sheetname "")
			)
			(fill
				(thermal_gap 0.5)
				(thermal_bridge_width 0.5)
				(island_removal_mode 0)
			)
			(polygon
				(pts
					(xy 166.497 3.81) (xy 167.005 3.81) (xy 167.005 4.191) (xy 166.497 4.191)
				)
			)
		)
		(zone
			(layer "B.Cu")
			(hatch none 0.5)
			(connect_pads
				(clearance 0)
			)
			(min_thickness 0.25)
			(keepout
				(tracks allowed)
				(vias not_allowed)
				(pads allowed)
				(copperpour not_allowed)
				(footprints allowed)
			)
			(placement
				(enabled no)
				(sheetname "")
			)
			(fill
				(thermal_gap 0.5)
				(thermal_bridge_width 0.5)
				(island_removal_mode 0)
			)
			(polygon
				(pts
					(xy 166.497 4.191) (xy 167.005 4.191) (xy 167.005 3.81) (xy 166.497 3.81)
				)
			)
		)
	)
	(footprint ""
		(layer "B.Cu")
		(at 355.3333 -146.82724)
		(property "Reference" "C7W9"
			(at 0 0 0)
			(layer "B.SilkS")
			(hide yes)
			(effects
				(font
					(size 1.27 1.27)
				)
				(justify mirror)
			)
		)
		(property "Value" "*"
			(at 0.0762 -6.2357 0)
			(unlocked yes)
			(layer "B.Fab")
			(hide yes)
			(effects
				(font
					(size 1.27 1.016)
					(thickness 0.1524)
				)
				(justify mirror)
			)
		)
		(property "Device Type" "SC22U16V5MX-4-GP_SMD-BCG5-SC22A"
			(at 0.0762 -8.2677 0)
			(unlocked yes)
			(layer "B.Fab")
			(hide yes)
			(effects
				(font
					(size 1.27 1.016)
					(thickness 0.1524)
				)
				(justify mirror)
			)
		)
		(duplicate_pad_numbers_are_jumpers no)
		(fp_line
			(start -0.635 0)
			(end 0.635 0)
			(stroke
				(width 0.508)
				(type default)
			)
			(layer "B.SilkS")
		)
		(fp_rect
			(start 0.9652 1.778)
			(end -0.9652 -1.778)
			(stroke
				(width 0)
				(type default)
			)
			(fill no)
			(layer "B.CrtYd")
		)
		(fp_poly
			(pts
				(xy 0.9652 -1.778) (xy -0.9652 -1.778) (xy -0.9652 1.778) (xy 0.9652 1.778)
			)
			(stroke
				(width 0)
				(type default)
			)
			(fill no)
			(layer "B.Fab")
		)
		(pad "1" smd rect
			(at 0 -0.9652 180)
			(size 1.397 1.143)
			(layers "B.Cu" "B.Mask" "B.Paste")
			(net "VR_FET_SW_P12V_STBY_PVDDQ_DEF")
		)
		(pad "2" smd rect
			(at 0 0.9652 180)
			(size 1.397 1.143)
			(layers "B.Cu" "B.Mask" "B.Paste")
			(net "GND")
		)
	)
	(footprint ""
		(layer "B.Cu")
		(at 402.209 -33.655)
		(property "Reference" "C25W36"
			(at -0.97536 0.76708 90)
			(unlocked yes)
			(layer "B.SilkS")
			(effects
				(font
					(size 0.4064 0.254)
					(thickness 0.1524)
				)
				(justify mirror)
			)
		)
		(property "Value" ""
			(at 0 0 0)
			(layer "B.Fab")
			(effects
				(font
					(size 1.27 1.27)
				)
				(justify mirror)
			)
		)
		(duplicate_pad_numbers_are_jumpers no)
		(fp_poly
			(pts
				(xy 0.4953 -0.2032) (xy -0.4953 -0.2032) (xy -0.4953 1.6002) (xy 0.4953 1.6002)
			)
			(stroke
				(width 0)
				(type default)
			)
			(fill no)
			(layer "B.CrtYd")
		)
		(fp_line
			(start -0.4953 -0.2032)
			(end -0.4953 1.6002)
			(stroke
				(width 0.1)
				(type default)
			)
			(layer "B.Fab")
		)
		(fp_line
			(start -0.4953 1.6002)
			(end 0.4953 1.6002)
			(stroke
				(width 0.1)
				(type default)
			)
			(layer "B.Fab")
		)
		(fp_line
			(start 0.4953 -0.2032)
			(end -0.4953 -0.2032)
			(stroke
				(width 0.1)
				(type default)
			)
			(layer "B.Fab")
		)
		(fp_line
			(start 0.4953 1.6002)
			(end 0.4953 -0.2032)
			(stroke
				(width 0.1)
				(type default)
			)
			(layer "B.Fab")
		)
		(pad "1" smd rect
			(at 0 0 180)
			(size 0.762 0.889)
			(layers "B.Cu" "B.Mask" "B.Paste")
			(net "VCC_DACAV3V3")
		)
		(pad "2" smd rect
			(at 0 1.397 180)
			(size 0.762 0.889)
			(layers "B.Cu" "B.Mask" "B.Paste")
			(net "GND")
		)
		(zone
			(layer "B.Cu")
			(hatch none 0.5)
			(connect_pads
				(clearance 0)
			)
			(min_thickness 0.25)
			(keepout
				(tracks not_allowed)
				(vias allowed)
				(pads allowed)
				(copperpour not_allowed)
				(footprints allowed)
			)
			(placement
				(enabled no)
				(sheetname "")
			)
			(fill
				(thermal_gap 0.5)
				(thermal_bridge_width 0.5)
				(island_removal_mode 0)
			)
			(polygon
				(pts
					(xy 402.59 -33.2105) (xy 401.828 -33.2105) (xy 401.828 -32.7025) (xy 402.59 -32.7025)
				)
			)
		)
	)
	(footprint ""
		(layer "B.Cu")
		(at 346.456 -104.267 180)
		(property "Reference" "C22W29"
			(at 0 0 0)
			(layer "B.SilkS")
			(hide yes)
			(effects
				(font
					(size 1.27 1.27)
				)
				(justify mirror)
			)
		)
		(property "Value" "*"
			(at 0.0762 -6.2357 180)
			(unlocked yes)
			(layer "B.Fab")
			(hide yes)
			(effects
				(font
					(size 1.27 1.016)
					(thickness 0.1524)
				)
				(justify mirror)
			)
		)
		(property "Device Type" "SC22U16V5MX-4-GP_SMD-BCG5-SC22A"
			(at 0.0762 -8.2677 180)
			(unlocked yes)
			(layer "B.Fab")
			(hide yes)
			(effects
				(font
					(size 1.27 1.016)
					(thickness 0.1524)
				)
				(justify mirror)
			)
		)
		(duplicate_pad_numbers_are_jumpers no)
		(fp_line
			(start -0.635 0)
			(end 0.635 0)
			(stroke
				(width 0.508)
				(type default)
			)
			(layer "B.SilkS")
		)
		(fp_rect
			(start 0.9652 1.778)
			(end -0.9652 -1.778)
			(stroke
				(width 0)
				(type default)
			)
			(fill no)
			(layer "B.CrtYd")
		)
		(fp_poly
			(pts
				(xy 0.9652 -1.778) (xy -0.9652 -1.778) (xy -0.9652 1.778) (xy 0.9652 1.778)
			)
			(stroke
				(width 0)
				(type default)
			)
			(fill no)
			(layer "B.Fab")
		)
		(pad "1" smd rect
			(at 0 -0.9652)
			(size 1.397 1.143)
			(layers "B.Cu" "B.Mask" "B.Paste")
			(net "VR_FET_SW_P12V_STBY_PVCCIO_CPU0")
		)
		(pad "2" smd rect
			(at 0 0.9652)
			(size 1.397 1.143)
			(layers "B.Cu" "B.Mask" "B.Paste")
			(net "GND")
		)
	)
)
